(kicad_pcb
	(version 20241229)
	(generator "pcbnew")
	(generator_version "9.0")
	(general
		(thickness 1.62)
		(legacy_teardrops no)
	)
	(paper "A3")
	(title_block
		(title "COM Express 7 Baseboard")
		(date "2025-02-04")
		(rev "1.1.2")
		(company "Antmicro Ltd")
		(comment 1 "www.antmicro.com")
		(comment 9 "footprints 542-545 of 802")
	)
	(layers
		(0 "F.Cu" signal)
		(4 "In1.Cu" signal)
		(6 "In2.Cu" signal)
		(8 "In3.Cu" signal)
		(10 "In4.Cu" signal)
		(12 "In5.Cu" signal)
		(14 "In6.Cu" signal)
		(2 "B.Cu" signal)
		(9 "F.Adhes" user "F.Adhesive")
		(11 "B.Adhes" user "B.Adhesive")
		(13 "F.Paste" user)
		(15 "B.Paste" user)
		(5 "F.SilkS" user "F.Silkscreen")
		(7 "B.SilkS" user "B.Silkscreen")
		(1 "F.Mask" user)
		(3 "B.Mask" user)
		(17 "Dwgs.User" user "User.Drawings")
		(19 "Cmts.User" user "User.Comments")
		(21 "Eco1.User" user "User.Eco1")
		(23 "Eco2.User" user "User.Eco2")
		(25 "Edge.Cuts" user)
		(27 "Margin" user)
		(31 "F.CrtYd" user "F.Courtyard")
		(29 "B.CrtYd" user "B.Courtyard")
		(35 "F.Fab" user)
		(33 "B.Fab" user)
	)
	(footprint "antmicro-footprints:R_0402_1005Metric"
		(layer "B.Cu")
		(at 99.3 74.81)
		(descr "Resistor SMD 0402")
		(tags "resistor SMD 0402")
		(property "Reference" "R152"
			(at -3.65 0.4 0)
			(layer "B.SilkS")
			(effects
				(font
					(size 0.7 0.7)
					(thickness 0.15)
				)
				(justify right bottom mirror)
			)
		)
		(property "Value" "R_10k_0402"
			(at -1.011843 -1.772047 0)
			(layer "B.Fab")
			(effects
				(font
					(size 0.7 0.7)
					(thickness 0.15)
				)
				(justify right bottom mirror)
			)
		)
		(property "Datasheet" "https://www.bourns.com/docs/product-datasheets/cr.pdf"
			(at 0 0 0)
			(layer "F.Fab")
			(hide yes)
			(effects
				(font
					(size 1.27 1.27)
					(thickness 0.15)
				)
			)
		)
		(property "Description" "SMD Chip Resistor, 10 kohm, ± 1%, 62.5 mW, 0402 [1005 Metric], Thick Film, General Purpose"
			(at 0 0 0)
			(layer "F.Fab")
			(hide yes)
			(effects
				(font
					(size 1.27 1.27)
					(thickness 0.15)
				)
			)
		)
		(property "Author" "Antmicro"
			(at 0 0 0)
			(layer "B.Fab")
			(hide yes)
			(effects
				(font
					(size 1 1)
					(thickness 0.15)
				)
				(justify mirror)
			)
		)
		(property "License" "Apache-2.0"
			(at 0 0 0)
			(layer "B.Fab")
			(hide yes)
			(effects
				(font
					(size 1 1)
					(thickness 0.15)
				)
				(justify mirror)
			)
		)
		(property "MPN" "CR0402-FX-1002GLF"
			(at 0 0 0)
			(layer "B.Fab")
			(hide yes)
			(effects
				(font
					(size 1 1)
					(thickness 0.15)
				)
				(justify mirror)
			)
		)
		(property "Manufacturer" "Bourns"
			(at 0 0 0)
			(layer "B.Fab")
			(hide yes)
			(effects
				(font
					(size 1 1)
					(thickness 0.15)
				)
				(justify mirror)
			)
		)
		(property "Tolerance" "1%"
			(at 0 0 0)
			(layer "B.Fab")
			(hide yes)
			(effects
				(font
					(size 1 1)
					(thickness 0.15)
				)
				(justify mirror)
			)
		)
		(property "Val" "10k"
			(at 0 0 0)
			(layer "B.Fab")
			(hide yes)
			(effects
				(font
					(size 1 1)
					(thickness 0.15)
				)
				(justify mirror)
			)
		)
		(sheetname "Misc")
		(sheetfile "misc.kicad_sch")
		(attr smd)
		(fp_rect
			(start -0.925 0.47)
			(end 0.925 -0.47)
			(stroke
				(width 0.05)
				(type default)
			)
			(fill no)
			(layer "B.CrtYd")
		)
		(fp_rect
			(start -0.5 0.25)
			(end 0.5 -0.25)
			(stroke
				(width 0.15)
				(type solid)
			)
			(fill no)
			(layer "B.Fab")
		)
		(pad "1" smd roundrect
			(at -0.48 0)
			(size 0.59 0.64)
			(layers "B.Cu" "B.Mask" "B.Paste")
			(roundrect_rratio 0.25)
			(net 539 "/Misc/~{PWR_OK}")
			(pintype "passive")
			(teardrops
				(best_length_ratio 0.2)
				(max_length 1)
				(best_width_ratio 0.9)
				(max_width 2)
				(curved_edges yes)
				(filter_ratio 0.9)
				(enabled yes)
				(allow_two_segments yes)
				(prefer_zone_connections yes)
			)
		)
		(pad "2" smd roundrect
			(at 0.48 0)
			(size 0.59 0.64)
			(layers "B.Cu" "B.Mask" "B.Paste")
			(roundrect_rratio 0.25)
			(net 133 "Net-(D18-C_{G})")
			(pintype "passive")
			(teardrops
				(best_length_ratio 0.2)
				(max_length 1)
				(best_width_ratio 0.9)
				(max_width 2)
				(curved_edges yes)
				(filter_ratio 0.9)
				(enabled yes)
				(allow_two_segments yes)
				(prefer_zone_connections yes)
			)
		)
	)
	(footprint "antmicro-footprints:R_0402_1005Metric"
		(layer "B.Cu")
		(at 99.3 78.81)
		(descr "Resistor SMD 0402")
		(tags "resistor SMD 0402")
		(property "Reference" "R142"
			(at -3.65 0.4 0)
			(layer "B.SilkS")
			(effects
				(font
					(size 0.7 0.7)
					(thickness 0.15)
				)
				(justify right bottom mirror)
			)
		)
		(property "Value" "R_10k_0402"
			(at -1.011843 -1.772047 0)
			(layer "B.Fab")
			(effects
				(font
					(size 0.7 0.7)
					(thickness 0.15)
				)
				(justify right bottom mirror)
			)
		)
		(property "Datasheet" "https://www.bourns.com/docs/product-datasheets/cr.pdf"
			(at 0 0 0)
			(layer "F.Fab")
			(hide yes)
			(effects
				(font
					(size 1.27 1.27)
					(thickness 0.15)
				)
			)
		)
		(property "Description" "SMD Chip Resistor, 10 kohm, ± 1%, 62.5 mW, 0402 [1005 Metric], Thick Film, General Purpose"
			(at 0 0 0)
			(layer "F.Fab")
			(hide yes)
			(effects
				(font
					(size 1.27 1.27)
					(thickness 0.15)
				)
			)
		)
		(property "Author" "Antmicro"
			(at 0 0 0)
			(layer "B.Fab")
			(hide yes)
			(effects
				(font
					(size 1 1)
					(thickness 0.15)
				)
				(justify mirror)
			)
		)
		(property "License" "Apache-2.0"
			(at 0 0 0)
			(layer "B.Fab")
			(hide yes)
			(effects
				(font
					(size 1 1)
					(thickness 0.15)
				)
				(justify mirror)
			)
		)
		(property "MPN" "CR0402-FX-1002GLF"
			(at 0 0 0)
			(layer "B.Fab")
			(hide yes)
			(effects
				(font
					(size 1 1)
					(thickness 0.15)
				)
				(justify mirror)
			)
		)
		(property "Manufacturer" "Bourns"
			(at 0 0 0)
			(layer "B.Fab")
			(hide yes)
			(effects
				(font
					(size 1 1)
					(thickness 0.15)
				)
				(justify mirror)
			)
		)
		(property "Tolerance" "1%"
			(at 0 0 0)
			(layer "B.Fab")
			(hide yes)
			(effects
				(font
					(size 1 1)
					(thickness 0.15)
				)
				(justify mirror)
			)
		)
		(property "Val" "10k"
			(at 0 0 0)
			(layer "B.Fab")
			(hide yes)
			(effects
				(font
					(size 1 1)
					(thickness 0.15)
				)
				(justify mirror)
			)
		)
		(sheetname "Misc")
		(sheetfile "misc.kicad_sch")
		(attr smd)
		(fp_rect
			(start -0.925 0.47)
			(end 0.925 -0.47)
			(stroke
				(width 0.05)
				(type default)
			)
			(fill no)
			(layer "B.CrtYd")
		)
		(fp_rect
			(start -0.5 0.25)
			(end 0.5 -0.25)
			(stroke
				(width 0.15)
				(type solid)
			)
			(fill no)
			(layer "B.Fab")
		)
		(pad "1" smd roundrect
			(at -0.48 0)
			(size 0.59 0.64)
			(layers "B.Cu" "B.Mask" "B.Paste")
			(roundrect_rratio 0.25)
			(net 944 "/GPIO expander/GPIOEX2")
			(pintype "passive")
			(teardrops
				(best_length_ratio 0.2)
				(max_length 1)
				(best_width_ratio 0.9)
				(max_width 2)
				(curved_edges yes)
				(filter_ratio 0.9)
				(enabled yes)
				(allow_two_segments yes)
				(prefer_zone_connections yes)
			)
		)
		(pad "2" smd roundrect
			(at 0.48 0)
			(size 0.59 0.64)
			(layers "B.Cu" "B.Mask" "B.Paste")
			(roundrect_rratio 0.25)
			(net 129 "Net-(D17-C_{R})")
			(pintype "passive")
			(teardrops
				(best_length_ratio 0.2)
				(max_length 1)
				(best_width_ratio 0.9)
				(max_width 2)
				(curved_edges yes)
				(filter_ratio 0.9)
				(enabled yes)
				(allow_two_segments yes)
				(prefer_zone_connections yes)
			)
		)
	)
	(footprint "antmicro-footprints:C_0402_1005Metric"
		(layer "B.Cu")
		(at 150.45 141.36 90)
		(descr "Capacitor SMD 0402")
		(tags "capacitor SMD 0402")
		(property "Reference" "C161"
			(at -3.7 0.4 90)
			(layer "B.SilkS")
			(effects
				(font
					(size 0.7 0.7)
					(thickness 0.15)
				)
				(justify right bottom mirror)
			)
		)
		(property "Value" "C_100n_0402"
			(at -1.022927 -2.155213 90)
			(layer "B.Fab")
			(effects
				(font
					(size 0.7 0.7)
					(thickness 0.15)
				)
				(justify right bottom mirror)
			)
		)
		(property "Datasheet" "https://www.murata.com/products/productdetail?partno=GRM155R61H104KE14%23"
			(at 0 0 90)
			(layer "F.Fab")
			(hide yes)
			(effects
				(font
					(size 1.27 1.27)
					(thickness 0.15)
				)
			)
		)
		(property "Author" "Antmicro"
			(at 291.81 -9.09 0)
			(layer "B.Fab")
			(hide yes)
			(effects
				(font
					(size 1 1)
					(thickness 0.15)
				)
				(justify mirror)
			)
		)
		(property "Dielectric" "X5R"
			(at 291.81 -9.09 0)
			(layer "B.Fab")
			(hide yes)
			(effects
				(font
					(size 1 1)
					(thickness 0.15)
				)
				(justify mirror)
			)
		)
		(property "License" "Apache-2.0"
			(at 291.81 -9.09 0)
			(layer "B.Fab")
			(hide yes)
			(effects
				(font
					(size 1 1)
					(thickness 0.15)
				)
				(justify mirror)
			)
		)
		(property "MPN" "GRM155R61H104KE14D"
			(at 291.81 -9.09 0)
			(layer "B.Fab")
			(hide yes)
			(effects
				(font
					(size 1 1)
					(thickness 0.15)
				)
				(justify mirror)
			)
		)
		(property "Manufacturer" "Murata"
			(at 291.81 -9.09 0)
			(layer "B.Fab")
			(hide yes)
			(effects
				(font
					(size 1 1)
					(thickness 0.15)
				)
				(justify mirror)
			)
		)
		(property "Public" "False"
			(at 291.81 -9.09 0)
			(layer "B.Fab")
			(hide yes)
			(effects
				(font
					(size 1 1)
					(thickness 0.15)
				)
				(justify mirror)
			)
		)
		(property "Val" "100n"
			(at 291.81 -9.09 0)
			(layer "B.Fab")
			(hide yes)
			(effects
				(font
					(size 1 1)
					(thickness 0.15)
				)
				(justify mirror)
			)
		)
		(property "Voltage" "50V"
			(at 291.81 -9.09 0)
			(layer "B.Fab")
			(hide yes)
			(effects
				(font
					(size 1 1)
					(thickness 0.15)
				)
				(justify mirror)
			)
		)
		(sheetname "KR to SFI #1")
		(sheetfile "kr_sfi.kicad_sch")
		(attr smd)
		(fp_rect
			(start -0.925 0.47)
			(end 0.925 -0.47)
			(stroke
				(width 0.05)
				(type default)
			)
			(fill no)
			(layer "B.CrtYd")
		)
		(fp_line
			(start 0.504 -0.248)
			(end 0.504 0.25)
			(stroke
				(width 0.15)
				(type solid)
			)
			(layer "B.Fab")
		)
		(fp_line
			(start -0.494 -0.248)
			(end 0.504 -0.248)
			(stroke
				(width 0.15)
				(type solid)
			)
			(layer "B.Fab")
		)
		(fp_line
			(start 0.504 0.25)
			(end -0.494 0.25)
			(stroke
				(width 0.15)
				(type solid)
			)
			(layer "B.Fab")
		)
		(fp_line
			(start -0.494 0.25)
			(end -0.494 -0.248)
			(stroke
				(width 0.15)
				(type solid)
			)
			(layer "B.Fab")
		)
		(pad "1" smd roundrect
			(at -0.48 0 90)
			(size 0.59 0.64)
			(layers "B.Cu" "B.Mask" "B.Paste")
			(roundrect_rratio 0.25)
			(net 1 "GND")
			(pintype "passive")
			(teardrops
				(best_length_ratio 0.2)
				(max_length 1)
				(best_width_ratio 0.9)
				(max_width 2)
				(curved_edges yes)
				(filter_ratio 0.9)
				(enabled yes)
				(allow_two_segments yes)
				(prefer_zone_connections yes)
			)
		)
		(pad "2" smd roundrect
			(at 0.48 0 90)
			(size 0.59 0.64)
			(layers "B.Cu" "B.Mask" "B.Paste")
			(roundrect_rratio 0.25)
			(net 74 "+1V0")
			(pintype "passive")
			(teardrops
				(best_length_ratio 0.2)
				(max_length 1)
				(best_width_ratio 0.9)
				(max_width 2)
				(curved_edges yes)
				(filter_ratio 0.9)
				(enabled yes)
				(allow_two_segments yes)
				(prefer_zone_connections yes)
			)
		)
	)
	(footprint "antmicro-footprints:R_0402_1005Metric"
		(layer "B.Cu")
		(at 144.25 138.06)
		(descr "Resistor SMD 0402")
		(tags "resistor SMD 0402")
		(property "Reference" "R263"
			(at -1.45 5.4 0)
			(layer "B.SilkS")
			(effects
				(font
					(size 0.7 0.7)
					(thickness 0.15)
				)
				(justify right bottom mirror)
			)
		)
		(property "Value" "R_10k_0402"
			(at -1.011843 -1.772047 0)
			(layer "B.Fab")
			(effects
				(font
					(size 0.7 0.7)
					(thickness 0.15)
				)
				(justify right bottom mirror)
			)
		)
		(property "Datasheet" "https://www.bourns.com/docs/product-datasheets/cr.pdf"
			(at 0 0 0)
			(layer "F.Fab")
			(hide yes)
			(effects
				(font
					(size 1.27 1.27)
					(thickness 0.15)
				)
			)
		)
		(property "Author" "Antmicro"
			(at 0 0 0)
			(layer "B.Fab")
			(hide yes)
			(effects
				(font
					(size 1 1)
					(thickness 0.15)
				)
				(justify mirror)
			)
		)
		(property "License" "Apache-2.0"
			(at 0 0 0)
			(layer "B.Fab")
			(hide yes)
			(effects
				(font
					(size 1 1)
					(thickness 0.15)
				)
				(justify mirror)
			)
		)
		(property "MPN" "CR0402-FX-1002GLF"
			(at 0 0 0)
			(layer "B.Fab")
			(hide yes)
			(effects
				(font
					(size 1 1)
					(thickness 0.15)
				)
				(justify mirror)
			)
		)
		(property "Manufacturer" "Bourns"
			(at 0 0 0)
			(layer "B.Fab")
			(hide yes)
			(effects
				(font
					(size 1 1)
					(thickness 0.15)
				)
				(justify mirror)
			)
		)
		(property "Public" "False"
			(at 0 0 0)
			(layer "B.Fab")
			(hide yes)
			(effects
				(font
					(size 1 1)
					(thickness 0.15)
				)
				(justify mirror)
			)
		)
		(property "Tolerance" "1%"
			(at 0 0 0)
			(layer "B.Fab")
			(hide yes)
			(effects
				(font
					(size 1 1)
					(thickness 0.15)
				)
				(justify mirror)
			)
		)
		(property "Val" "10k"
			(at 0 0 0)
			(layer "B.Fab")
			(hide yes)
			(effects
				(font
					(size 1 1)
					(thickness 0.15)
				)
				(justify mirror)
			)
		)
		(sheetname "KR to SFI #1")
		(sheetfile "kr_sfi.kicad_sch")
		(attr smd)
		(fp_rect
			(start -0.925 0.47)
			(end 0.925 -0.47)
			(stroke
				(width 0.05)
				(type default)
			)
			(fill no)
			(layer "B.CrtYd")
		)
		(fp_rect
			(start -0.5 0.25)
			(end 0.5 -0.25)
			(stroke
				(width 0.15)
				(type solid)
			)
			(fill no)
			(layer "B.Fab")
		)
		(pad "1" smd roundrect
			(at -0.48 0)
			(size 0.59 0.64)
			(layers "B.Cu" "B.Mask" "B.Paste")
			(roundrect_rratio 0.25)
			(net 1 "GND")
			(pintype "passive")
			(teardrops
				(best_length_ratio 0.2)
				(max_length 1)
				(best_width_ratio 0.9)
				(max_width 2)
				(curved_edges yes)
				(filter_ratio 0.9)
				(enabled yes)
				(allow_two_segments yes)
				(prefer_zone_connections yes)
			)
		)
		(pad "2" smd roundrect
			(at 0.48 0)
			(size 0.59 0.64)
			(layers "B.Cu" "B.Mask" "B.Paste")
			(roundrect_rratio 0.25)
			(net 656 "Net-(U43C-PRTAD1)")
			(pintype "passive")
			(teardrops
				(best_length_ratio 0.2)
				(max_length 1)
				(best_width_ratio 0.9)
				(max_width 2)
				(curved_edges yes)
				(filter_ratio 0.9)
				(enabled yes)
				(allow_two_segments yes)
				(prefer_zone_connections yes)
			)
		)
	)
)
